(kicad_pcb
	(version 20260206)
	(generator "pcbnew")
	(generator_version "10.0")
	(general
		(thickness 1.6)
		(legacy_teardrops no)
	)
	(paper "A4")
	(title_block
		(title "04192023_DAF0TMB3IC0_F0TG_MB_C_brd_V02_OCP.brd")
		(comment 1 "Grand Teton / footprints 6525-6530 of 8354")
	)
	(layers
		(0 "F.Cu" signal "TOP")
		(4 "In1.Cu" signal "GND")
		(6 "In2.Cu" signal "IN1")
		(8 "In3.Cu" signal "GND1")
		(10 "In4.Cu" signal "IN2")
		(12 "In5.Cu" signal "GND2")
		(14 "In6.Cu" signal "IN3")
		(16 "In7.Cu" signal "GND3")
		(18 "In8.Cu" signal "VCC")
		(20 "In9.Cu" signal "VCC1")
		(22 "In10.Cu" signal "GND4")
		(24 "In11.Cu" signal "IN4")
		(26 "In12.Cu" signal "GND5")
		(28 "In13.Cu" signal "IN5")
		(30 "In14.Cu" signal "GND6")
		(32 "In15.Cu" signal "IN6")
		(34 "In16.Cu" signal "GND7")
		(2 "B.Cu" signal "BOTTOM")
		(9 "F.Adhes" user "F.Adhesive")
		(11 "B.Adhes" user "B.Adhesive")
		(13 "F.Paste" user "Package Geometry/Pastemask Top")
		(15 "B.Paste" user "Package Geometry/Pastemask Bottom")
		(5 "F.SilkS" user "Ref Des/Silkscreen Top")
		(7 "B.SilkS" user "Ref Des/Silkscreen Bottom")
		(1 "F.Mask" user "Board Geometry/Soldermask Top")
		(3 "B.Mask" user "Board Geometry/Soldermask Bottom")
		(17 "Dwgs.User" user "User.Drawings")
		(19 "Cmts.User" user "User.Comments")
		(21 "Eco1.User" user "User.Eco1")
		(23 "Eco2.User" user "User.Eco2")
		(25 "Edge.Cuts" user "Board Geometry/Outline")
		(27 "Margin" user)
		(31 "F.CrtYd" user "Package Geometry/Place Bound Top")
		(29 "B.CrtYd" user "Package Geometry/Place Bound Bottom")
		(35 "F.Fab" user "Ref Des/Assembly Top")
		(33 "B.Fab" user "Ref Des/Assembly Bottom")
	)
	(footprint ""
		(layer "B.Cu")
		(at 102.378764 -258.830318 180)
		(property "Reference" "C2484"
			(at 0 0 0)
			(layer "B.SilkS")
			(hide yes)
			(effects
				(font
					(size 1.27 1.27)
				)
				(justify mirror)
			)
		)
		(property "Value" ""
			(at 0 0 0)
			(layer "B.Fab")
			(effects
				(font
					(size 1.27 1.27)
				)
				(justify mirror)
			)
		)
		(duplicate_pad_numbers_are_jumpers no)
		(fp_line
			(start 0.7874 0.4064)
			(end 0.7874 -0.4064)
			(stroke
				(width 0.1524)
				(type default)
			)
			(layer "B.SilkS")
		)
		(fp_line
			(start 0.7874 -0.4064)
			(end -0.7874 -0.4064)
			(stroke
				(width 0.1524)
				(type default)
			)
			(layer "B.SilkS")
		)
		(fp_line
			(start -0.7874 0.4064)
			(end 0.7874 0.4064)
			(stroke
				(width 0.1524)
				(type default)
			)
			(layer "B.SilkS")
		)
		(fp_line
			(start -0.7874 -0.4064)
			(end -0.7874 0.4064)
			(stroke
				(width 0.1524)
				(type default)
			)
			(layer "B.SilkS")
		)
		(fp_line
			(start 0.67945 0.3048)
			(end 0.67945 -0.305054)
			(stroke
				(width 0.1)
				(type default)
			)
			(layer "B.Fab")
		)
		(fp_line
			(start 0.67945 -0.305054)
			(end 0.12065 -0.305054)
			(stroke
				(width 0.1)
				(type default)
			)
			(layer "B.Fab")
		)
		(fp_line
			(start 0.12065 0.3048)
			(end 0.67945 0.3048)
			(stroke
				(width 0.1)
				(type default)
			)
			(layer "B.Fab")
		)
		(fp_line
			(start 0.12065 0.2794)
			(end 0.12065 0.3048)
			(stroke
				(width 0.1)
				(type default)
			)
			(layer "B.Fab")
		)
		(fp_line
			(start 0.12065 -0.2794)
			(end -0.12065 -0.2794)
			(stroke
				(width 0.1)
				(type default)
			)
			(layer "B.Fab")
		)
		(fp_line
			(start 0.12065 -0.305054)
			(end 0.12065 -0.2794)
			(stroke
				(width 0.1)
				(type default)
			)
			(layer "B.Fab")
		)
		(fp_line
			(start -0.120396 0.3048)
			(end -0.120396 0.2794)
			(stroke
				(width 0.1)
				(type default)
			)
			(layer "B.Fab")
		)
		(fp_line
			(start -0.120396 0.2794)
			(end 0.12065 0.2794)
			(stroke
				(width 0.1)
				(type default)
			)
			(layer "B.Fab")
		)
		(fp_line
			(start -0.12065 -0.2794)
			(end -0.12065 -0.3048)
			(stroke
				(width 0.1)
				(type default)
			)
			(layer "B.Fab")
		)
		(fp_line
			(start -0.12065 -0.3048)
			(end -0.67945 -0.3048)
			(stroke
				(width 0.1)
				(type default)
			)
			(layer "B.Fab")
		)
		(fp_line
			(start -0.67945 0.3048)
			(end -0.120396 0.3048)
			(stroke
				(width 0.1)
				(type default)
			)
			(layer "B.Fab")
		)
		(fp_line
			(start -0.67945 -0.3048)
			(end -0.67945 0.3048)
			(stroke
				(width 0.1)
				(type default)
			)
			(layer "B.Fab")
		)
		(pad "1" smd circle
			(at 0.40005 0)
			(size 0 0)
			(layers "B.Cu" "B.Mask" "B.Paste")
			(net "PVDDIO_P1")
		)
		(pad "2" smd circle
			(at -0.40005 0)
			(size 0 0)
			(layers "B.Cu" "B.Mask" "B.Paste")
			(net "GND")
		)
	)
	(footprint ""
		(layer "B.Cu")
		(at 209.295746 -77.263752)
		(property "Reference" "U222"
			(at 2.032 -3.27533 0)
			(unlocked yes)
			(layer "B.SilkS")
			(effects
				(font
					(size 0.7874 0.5842)
					(thickness 0.1524)
				)
				(justify left mirror)
			)
		)
		(property "Value" ""
			(at 0 0 0)
			(layer "B.Fab")
			(effects
				(font
					(size 1.27 1.27)
				)
				(justify mirror)
			)
		)
		(duplicate_pad_numbers_are_jumpers no)
		(fp_line
			(start -2.0066 -2.5527)
			(end -2.0066 2.5527)
			(stroke
				(width 0.1524)
				(type default)
			)
			(layer "B.SilkS")
		)
		(fp_line
			(start -2.0066 2.5527)
			(end 2.0066 2.5527)
			(stroke
				(width 0.1524)
				(type default)
			)
			(layer "B.SilkS")
		)
		(fp_line
			(start -0.5715 -2.5527)
			(end -2.0066 -2.5527)
			(stroke
				(width 0.1524)
				(type default)
			)
			(layer "B.SilkS")
		)
		(fp_line
			(start 0 -1.9812)
			(end -0.5715 -2.5527)
			(stroke
				(width 0.1524)
				(type default)
			)
			(layer "B.SilkS")
		)
		(fp_line
			(start 0.5715 -2.5527)
			(end 0 -1.9812)
			(stroke
				(width 0.1524)
				(type default)
			)
			(layer "B.SilkS")
		)
		(fp_line
			(start 2.0066 -2.5527)
			(end 0.5715 -2.5527)
			(stroke
				(width 0.1524)
				(type default)
			)
			(layer "B.SilkS")
		)
		(fp_line
			(start 2.0066 2.5527)
			(end 2.0066 -2.5527)
			(stroke
				(width 0.1524)
				(type default)
			)
			(layer "B.SilkS")
		)
		(fp_poly
			(pts
				(xy 3.81 -1.905) (xy 4.36372 -2.233168) (xy 4.36372 -1.608328)
			)
			(stroke
				(width 0)
				(type default)
			)
			(fill yes)
			(layer "B.SilkS")
		)
		(fp_line
			(start -2.249932 -2.549906)
			(end -2.249932 2.549906)
			(stroke
				(width 0.1)
				(type default)
			)
			(layer "B.Fab")
		)
		(fp_line
			(start -2.249932 2.549906)
			(end 2.249932 2.549906)
			(stroke
				(width 0.1)
				(type default)
			)
			(layer "B.Fab")
		)
		(fp_line
			(start 2.249932 -2.549906)
			(end -2.249932 -2.549906)
			(stroke
				(width 0.1)
				(type default)
			)
			(layer "B.Fab")
		)
		(fp_line
			(start 2.249932 2.549906)
			(end 2.249932 -2.549906)
			(stroke
				(width 0.1)
				(type default)
			)
			(layer "B.Fab")
		)
		(fp_poly
			(pts
				(xy 4.36372 -1.608328) (xy 4.36372 -2.233168) (xy 3.81 -1.905)
			)
			(stroke
				(width 0)
				(type default)
			)
			(fill yes)
			(layer "B.Fab")
		)
		(pad "1" smd rect
			(at 2.921 -1.949958 270)
			(size 0.3556 1.4986)
			(layers "B.Cu" "B.Mask" "B.Paste")
			(net "FB_BMC_ISOLATE1")
		)
		(pad "2" smd rect
			(at 2.921 -1.299972 270)
			(size 0.3556 1.4986)
			(layers "B.Cu" "B.Mask" "B.Paste")
			(net "NCSI_BMC_RXD1_R1")
		)
		(pad "3" smd rect
			(at 2.921 -0.649986 270)
			(size 0.3556 1.4986)
			(layers "B.Cu" "B.Mask" "B.Paste")
			(net "NCSI_OCP_V3_2_RXD1")
		)
		(pad "4" smd rect
			(at 2.921 0 270)
			(size 0.3556 1.4986)
			(layers "B.Cu" "B.Mask" "B.Paste")
			(net "FB_BMC_ISOLATE1")
		)
		(pad "5" smd rect
			(at 2.921 0.649986 270)
			(size 0.3556 1.4986)
			(layers "B.Cu" "B.Mask" "B.Paste")
			(net "NCSI_BMC_RXD0_R1")
		)
		(pad "6" smd rect
			(at 2.921 1.299972 270)
			(size 0.3556 1.4986)
			(layers "B.Cu" "B.Mask" "B.Paste")
			(net "NCSI_OCP_V3_2_RXD0")
		)
		(pad "7" smd rect
			(at 2.921 1.949958 270)
			(size 0.3556 1.4986)
			(layers "B.Cu" "B.Mask" "B.Paste")
			(net "GND")
		)
		(pad "8" smd rect
			(at -2.921 1.949958 270)
			(size 0.3556 1.4986)
			(layers "B.Cu" "B.Mask" "B.Paste")
			(net "NCSI_OCP_V3_2_CRS_DV")
		)
		(pad "9" smd rect
			(at -2.921 1.299972 270)
			(size 0.3556 1.4986)
			(layers "B.Cu" "B.Mask" "B.Paste")
			(net "NCSI_BMC_CRS_DV_R1")
		)
		(pad "10" smd rect
			(at -2.921 0.649986 270)
			(size 0.3556 1.4986)
			(layers "B.Cu" "B.Mask" "B.Paste")
			(net "FB_BMC_ISOLATE1")
		)
		(pad "11" smd rect
			(at -2.921 0 270)
			(size 0.3556 1.4986)
			(layers "B.Cu" "B.Mask" "B.Paste")
			(net "OCP_V3_2_ISO1_RBT_ARB_IN")
		)
		(pad "12" smd rect
			(at -2.921 -0.649986 270)
			(size 0.3556 1.4986)
			(layers "B.Cu" "B.Mask" "B.Paste")
			(net "OCP_V3_2_RBT_ARB_IN_R")
		)
		(pad "13" smd rect
			(at -2.921 -1.299972 270)
			(size 0.3556 1.4986)
			(layers "B.Cu" "B.Mask" "B.Paste")
			(net "FB_BMC_ISOLATE1")
		)
		(pad "14" smd rect
			(at -2.921 -1.949958 270)
			(size 0.3556 1.4986)
			(layers "B.Cu" "B.Mask" "B.Paste")
			(net "P3V3_AUX")
		)
	)
	(footprint ""
		(layer "B.Cu")
		(at 400.358102 -152.29078 -90)
		(property "Reference" "R4640"
			(at 0 0 90)
			(layer "B.SilkS")
			(hide yes)
			(effects
				(font
					(size 1.27 1.27)
				)
				(justify mirror)
			)
		)
		(property "Value" ""
			(at 0 0 90)
			(layer "B.Fab")
			(effects
				(font
					(size 1.27 1.27)
				)
				(justify mirror)
			)
		)
		(duplicate_pad_numbers_are_jumpers no)
		(fp_line
			(start -2.234946 0.9271)
			(end 2.234946 0.9271)
			(stroke
				(width 0.1524)
				(type default)
			)
			(layer "B.SilkS")
		)
		(fp_line
			(start 2.234946 0.9271)
			(end 2.234946 -0.9271)
			(stroke
				(width 0.1524)
				(type default)
			)
			(layer "B.SilkS")
		)
		(fp_line
			(start -2.234946 -0.9271)
			(end -2.234946 0.9271)
			(stroke
				(width 0.1524)
				(type default)
			)
			(layer "B.SilkS")
		)
		(fp_line
			(start 2.234946 -0.9271)
			(end -2.234946 -0.9271)
			(stroke
				(width 0.1524)
				(type default)
			)
			(layer "B.SilkS")
		)
		(fp_line
			(start -1.575054 0.824992)
			(end -1.575054 -0.824992)
			(stroke
				(width 0.1)
				(type default)
			)
			(layer "B.Fab")
		)
		(fp_line
			(start 1.575054 0.824992)
			(end -1.575054 0.824992)
			(stroke
				(width 0.1)
				(type default)
			)
			(layer "B.Fab")
		)
		(fp_line
			(start -1.575054 -0.824992)
			(end 1.575054 -0.824992)
			(stroke
				(width 0.1)
				(type default)
			)
			(layer "B.Fab")
		)
		(fp_line
			(start 1.575054 -0.824992)
			(end 1.575054 0.824992)
			(stroke
				(width 0.1)
				(type default)
			)
			(layer "B.Fab")
		)
		(pad "1" smd rect
			(at 1.599946 0 90)
			(size 1.016 1.6002)
			(layers "B.Cu" "B.Mask" "B.Paste")
			(net "P5V")
		)
		(pad "2" smd rect
			(at -1.599946 0 90)
			(size 1.016 1.6002)
			(layers "B.Cu" "B.Mask" "B.Paste")
			(net "VR_P5V_EN_D")
		)
	)
	(footprint ""
		(layer "B.Cu")
		(at 378.250958 -205.101952 90)
		(property "Reference" "C212"
			(at 0 0 90)
			(layer "B.SilkS")
			(hide yes)
			(effects
				(font
					(size 1.27 1.27)
				)
				(justify mirror)
			)
		)
		(property "Value" ""
			(at 0 0 90)
			(layer "B.Fab")
			(effects
				(font
					(size 1.27 1.27)
				)
				(justify mirror)
			)
		)
		(duplicate_pad_numbers_are_jumpers no)
		(fp_line
			(start 0.7874 -0.4064)
			(end -0.7874 -0.4064)
			(stroke
				(width 0.1524)
				(type default)
			)
			(layer "B.SilkS")
		)
		(fp_line
			(start -0.7874 -0.4064)
			(end -0.7874 0.4064)
			(stroke
				(width 0.1524)
				(type default)
			)
			(layer "B.SilkS")
		)
		(fp_line
			(start 0.7874 0.4064)
			(end 0.7874 -0.4064)
			(stroke
				(width 0.1524)
				(type default)
			)
			(layer "B.SilkS")
		)
		(fp_line
			(start -0.7874 0.4064)
			(end 0.7874 0.4064)
			(stroke
				(width 0.1524)
				(type default)
			)
			(layer "B.SilkS")
		)
		(fp_line
			(start 0.67945 -0.305054)
			(end 0.12065 -0.305054)
			(stroke
				(width 0.1)
				(type default)
			)
			(layer "B.Fab")
		)
		(fp_line
			(start 0.12065 -0.305054)
			(end 0.12065 -0.2794)
			(stroke
				(width 0.1)
				(type default)
			)
			(layer "B.Fab")
		)
		(fp_line
			(start -0.12065 -0.3048)
			(end -0.67945 -0.3048)
			(stroke
				(width 0.1)
				(type default)
			)
			(layer "B.Fab")
		)
		(fp_line
			(start -0.67945 -0.3048)
			(end -0.67945 0.3048)
			(stroke
				(width 0.1)
				(type default)
			)
			(layer "B.Fab")
		)
		(fp_line
			(start 0.12065 -0.2794)
			(end -0.12065 -0.2794)
			(stroke
				(width 0.1)
				(type default)
			)
			(layer "B.Fab")
		)
		(fp_line
			(start -0.12065 -0.2794)
			(end -0.12065 -0.3048)
			(stroke
				(width 0.1)
				(type default)
			)
			(layer "B.Fab")
		)
		(fp_line
			(start 0.12065 0.2794)
			(end 0.12065 0.3048)
			(stroke
				(width 0.1)
				(type default)
			)
			(layer "B.Fab")
		)
		(fp_line
			(start -0.120396 0.2794)
			(end 0.12065 0.2794)
			(stroke
				(width 0.1)
				(type default)
			)
			(layer "B.Fab")
		)
		(fp_line
			(start 0.67945 0.3048)
			(end 0.67945 -0.305054)
			(stroke
				(width 0.1)
				(type default)
			)
			(layer "B.Fab")
		)
		(fp_line
			(start 0.12065 0.3048)
			(end 0.67945 0.3048)
			(stroke
				(width 0.1)
				(type default)
			)
			(layer "B.Fab")
		)
		(fp_line
			(start -0.120396 0.3048)
			(end -0.120396 0.2794)
			(stroke
				(width 0.1)
				(type default)
			)
			(layer "B.Fab")
		)
		(fp_line
			(start -0.67945 0.3048)
			(end -0.120396 0.3048)
			(stroke
				(width 0.1)
				(type default)
			)
			(layer "B.Fab")
		)
		(pad "1" smd circle
			(at 0.40005 0 270)
			(size 0 0)
			(layers "B.Cu" "B.Mask" "B.Paste")
			(net "JTAG_CPU0_DBREQ_N")
		)
		(pad "2" smd circle
			(at -0.40005 0 270)
			(size 0 0)
			(layers "B.Cu" "B.Mask" "B.Paste")
			(net "GND")
		)
	)
	(footprint ""
		(layer "B.Cu")
		(at 131.153154 -152.724612 90)
		(property "Reference" "PC352_3"
			(at 0 0 90)
			(layer "B.SilkS")
			(hide yes)
			(effects
				(font
					(size 1.27 1.27)
				)
				(justify mirror)
			)
		)
		(property "Value" ""
			(at 0 0 90)
			(layer "B.Fab")
			(effects
				(font
					(size 1.27 1.27)
				)
				(justify mirror)
			)
		)
		(duplicate_pad_numbers_are_jumpers no)
		(fp_line
			(start 1.524 -0.762)
			(end -1.524 -0.762)
			(stroke
				(width 0.1524)
				(type default)
			)
			(layer "B.SilkS")
		)
		(fp_line
			(start -1.524 -0.762)
			(end -1.524 0.762)
			(stroke
				(width 0.1524)
				(type default)
			)
			(layer "B.SilkS")
		)
		(fp_line
			(start 1.524 0.762)
			(end 1.524 -0.762)
			(stroke
				(width 0.1524)
				(type default)
			)
			(layer "B.SilkS")
		)
		(fp_line
			(start -1.524 0.762)
			(end 1.524 0.762)
			(stroke
				(width 0.1524)
				(type default)
			)
			(layer "B.SilkS")
		)
		(fp_line
			(start 1.1049 -0.724916)
			(end 1.1049 0.724916)
			(stroke
				(width 0.1)
				(type default)
			)
			(layer "B.Fab")
		)
		(fp_line
			(start -1.1049 -0.724916)
			(end 1.1049 -0.724916)
			(stroke
				(width 0.1)
				(type default)
			)
			(layer "B.Fab")
		)
		(fp_line
			(start 1.1049 0.724916)
			(end -1.1049 0.724916)
			(stroke
				(width 0.1)
				(type default)
			)
			(layer "B.Fab")
		)
		(fp_line
			(start -1.1049 0.724916)
			(end -1.1049 -0.724916)
			(stroke
				(width 0.1)
				(type default)
			)
			(layer "B.Fab")
		)
		(pad "1" smd rect
			(at 0.889 0 90)
			(size 1.016 1.27)
			(layers "B.Cu" "B.Mask" "B.Paste")
			(net "SW_P12V_AUX_PVDDCR_SOC_P1_FLT")
		)
		(pad "2" smd rect
			(at -0.889 0 90)
			(size 1.016 1.27)
			(layers "B.Cu" "B.Mask" "B.Paste")
			(net "GND")
		)
	)
	(footprint ""
		(layer "B.Cu")
		(at 188.310012 -13.60043 -90)
		(property "Reference" "R6002"
			(at 0 0 90)
			(layer "B.SilkS")
			(hide yes)
			(effects
				(font
					(size 1.27 1.27)
				)
				(justify mirror)
			)
		)
		(property "Value" ""
			(at 0 0 90)
			(layer "B.Fab")
			(effects
				(font
					(size 1.27 1.27)
				)
				(justify mirror)
			)
		)
		(duplicate_pad_numbers_are_jumpers no)
		(fp_line
			(start -0.7874 0.4064)
			(end 0.7874 0.4064)
			(stroke
				(width 0.1524)
				(type default)
			)
			(layer "B.SilkS")
		)
		(fp_line
			(start 0.7874 0.4064)
			(end 0.7874 -0.4064)
			(stroke
				(width 0.1524)
				(type default)
			)
			(layer "B.SilkS")
		)
		(fp_line
			(start -0.7874 -0.4064)
			(end -0.7874 0.4064)
			(stroke
				(width 0.1524)
				(type default)
			)
			(layer "B.SilkS")
		)
		(fp_line
			(start 0.7874 -0.4064)
			(end -0.7874 -0.4064)
			(stroke
				(width 0.1524)
				(type default)
			)
			(layer "B.SilkS")
		)
		(fp_line
			(start -0.67945 0.3048)
			(end -0.120396 0.3048)
			(stroke
				(width 0.1)
				(type default)
			)
			(layer "B.Fab")
		)
		(fp_line
			(start -0.120396 0.3048)
			(end -0.120396 0.2794)
			(stroke
				(width 0.1)
				(type default)
			)
			(layer "B.Fab")
		)
		(fp_line
			(start 0.12065 0.3048)
			(end 0.67945 0.3048)
			(stroke
				(width 0.1)
				(type default)
			)
			(layer "B.Fab")
		)
		(fp_line
			(start 0.67945 0.3048)
			(end 0.67945 -0.305054)
			(stroke
				(width 0.1)
				(type default)
			)
			(layer "B.Fab")
		)
		(fp_line
			(start -0.120396 0.2794)
			(end 0.12065 0.2794)
			(stroke
				(width 0.1)
				(type default)
			)
			(layer "B.Fab")
		)
		(fp_line
			(start 0.12065 0.2794)
			(end 0.12065 0.3048)
			(stroke
				(width 0.1)
				(type default)
			)
			(layer "B.Fab")
		)
		(fp_line
			(start -0.12065 -0.2794)
			(end -0.12065 -0.3048)
			(stroke
				(width 0.1)
				(type default)
			)
			(layer "B.Fab")
		)
		(fp_line
			(start 0.12065 -0.2794)
			(end -0.12065 -0.2794)
			(stroke
				(width 0.1)
				(type default)
			)
			(layer "B.Fab")
		)
		(fp_line
			(start -0.67945 -0.3048)
			(end -0.67945 0.3048)
			(stroke
				(width 0.1)
				(type default)
			)
			(layer "B.Fab")
		)
		(fp_line
			(start -0.12065 -0.3048)
			(end -0.67945 -0.3048)
			(stroke
				(width 0.1)
				(type default)
			)
			(layer "B.Fab")
		)
		(fp_line
			(start 0.12065 -0.305054)
			(end 0.12065 -0.2794)
			(stroke
				(width 0.1)
				(type default)
			)
			(layer "B.Fab")
		)
		(fp_line
			(start 0.67945 -0.305054)
			(end 0.12065 -0.305054)
			(stroke
				(width 0.1)
				(type default)
			)
			(layer "B.Fab")
		)
		(pad "1" smd circle
			(at 0.40005 0 90)
			(size 0 0)
			(layers "B.Cu" "B.Mask" "B.Paste")
			(net "I3C_SCM_1_SCL")
		)
		(pad "2" smd circle
			(at -0.40005 0 90)
			(size 0 0)
			(layers "B.Cu" "B.Mask" "B.Paste")
			(net "I3C_SCM_1_R_SCL")
		)
	)
)
